(kicad_pcb
	(version 20241229)
	(generator "pcbnew")
	(generator_version "9.0")
	(general
		(thickness 1.6296)
		(legacy_teardrops no)
	)
	(paper "A3")
	(title_block
		(title "Thunderbolt to 10GbE adapter")
		(date "2026-04-21")
		(rev "1.1.0")
		(company "Antmicro Ltd")
		(comment 1 "www.antmicro.com")
		(comment 9 "footprints 402-406 of 703")
	)
	(layers
		(0 "F.Cu" signal)
		(4 "In1.Cu" signal)
		(6 "In2.Cu" signal)
		(8 "In3.Cu" signal)
		(10 "In4.Cu" signal)
		(12 "In5.Cu" signal)
		(14 "In6.Cu" signal)
		(2 "B.Cu" signal)
		(9 "F.Adhes" user "F.Adhesive")
		(11 "B.Adhes" user "B.Adhesive")
		(13 "F.Paste" user)
		(15 "B.Paste" user)
		(5 "F.SilkS" user "F.Silkscreen")
		(7 "B.SilkS" user "B.Silkscreen")
		(1 "F.Mask" user)
		(3 "B.Mask" user)
		(17 "Dwgs.User" user "User.Drawings")
		(19 "Cmts.User" user "User.Comments")
		(21 "Eco1.User" user "User.Eco1")
		(23 "Eco2.User" user "User.Eco2")
		(25 "Edge.Cuts" user)
		(27 "Margin" user)
		(31 "F.CrtYd" user "F.Courtyard")
		(29 "B.CrtYd" user "B.Courtyard")
		(35 "F.Fab" user)
		(33 "B.Fab" user)
	)
	(footprint "antmicro-footprints:C_0402_1005Metric"
		(layer "B.Cu")
		(at 154.261865 88.265117 180)
		(descr "Capacitor SMD 0402")
		(tags "capacitor SMD 0402")
		(property "Reference" "C195"
			(at -17.938134 -9.464883 0)
			(layer "B.SilkS")
			(effects
				(font
					(size 0.7 0.7)
					(thickness 0.15)
				)
				(justify mirror)
			)
		)
		(property "Value" "C_1u_25V_0402"
			(at -1.022927 -2.155213 0)
			(layer "B.Fab")
			(effects
				(font
					(size 0.7 0.7)
					(thickness 0.15)
				)
				(justify left bottom mirror)
			)
		)
		(property "Datasheet" "https://www.murata.com/products/productdetail?partno=GRM155R61E105KE11%23"
			(at 0 0 0)
			(layer "B.Fab")
			(hide yes)
			(effects
				(font
					(size 1.27 1.27)
					(thickness 0.15)
				)
				(justify mirror)
			)
		)
		(property "Description" "SMD Multilayer Ceramic Capacitor, 1 µF, 25 V, 0402 [1005 Metric], ± 10%, X5R, GRM Series"
			(at 0 0 0)
			(layer "B.Fab")
			(hide yes)
			(effects
				(font
					(size 1.27 1.27)
					(thickness 0.15)
				)
				(justify mirror)
			)
		)
		(property "MPN" "GRM155R61E105KE11J"
			(at 0 0 180)
			(unlocked yes)
			(layer "B.Fab")
			(hide yes)
			(effects
				(font
					(size 1 1)
					(thickness 0.15)
				)
				(justify mirror)
			)
		)
		(property "Manufacturer" "Murata"
			(at 0 0 180)
			(unlocked yes)
			(layer "B.Fab")
			(hide yes)
			(effects
				(font
					(size 1 1)
					(thickness 0.15)
				)
				(justify mirror)
			)
		)
		(property "License" "Apache-2.0"
			(at 0 0 180)
			(unlocked yes)
			(layer "B.Fab")
			(hide yes)
			(effects
				(font
					(size 1 1)
					(thickness 0.15)
				)
				(justify mirror)
			)
		)
		(property "Author" "Antmicro"
			(at 0 0 180)
			(unlocked yes)
			(layer "B.Fab")
			(hide yes)
			(effects
				(font
					(size 1 1)
					(thickness 0.15)
				)
				(justify mirror)
			)
		)
		(property "Val" "1u"
			(at 0 0 180)
			(unlocked yes)
			(layer "B.Fab")
			(hide yes)
			(effects
				(font
					(size 1 1)
					(thickness 0.15)
				)
				(justify mirror)
			)
		)
		(property "Voltage" "25V"
			(at 0 0 180)
			(unlocked yes)
			(layer "B.Fab")
			(hide yes)
			(effects
				(font
					(size 1 1)
					(thickness 0.15)
				)
				(justify mirror)
			)
		)
		(property "Dielectric" "X5R"
			(at 0 0 180)
			(unlocked yes)
			(layer "B.Fab")
			(hide yes)
			(effects
				(font
					(size 1 1)
					(thickness 0.15)
				)
				(justify mirror)
			)
		)
		(sheetname "/X710-AT2 power/")
		(sheetfile "x710-at2-power.kicad_sch")
		(attr smd)
		(fp_rect
			(start -0.925 0.47)
			(end 0.925 -0.47)
			(stroke
				(width 0.05)
				(type default)
			)
			(fill no)
			(layer "B.CrtYd")
		)
		(fp_line
			(start 0.504 0.25)
			(end 0.504 -0.248)
			(stroke
				(width 0.15)
				(type solid)
			)
			(layer "B.Fab")
		)
		(fp_line
			(start 0.504 -0.248)
			(end -0.494 -0.248)
			(stroke
				(width 0.15)
				(type solid)
			)
			(layer "B.Fab")
		)
		(fp_line
			(start -0.494 0.25)
			(end 0.504 0.25)
			(stroke
				(width 0.15)
				(type solid)
			)
			(layer "B.Fab")
		)
		(fp_line
			(start -0.494 -0.248)
			(end -0.494 0.25)
			(stroke
				(width 0.15)
				(type solid)
			)
			(layer "B.Fab")
		)
		(fp_text user "License: Apache-2.0"
			(at -0.939 -5.799 0)
			(layer "B.Fab")
			(effects
				(font
					(size 0.7 0.7)
					(thickness 0.15)
				)
				(justify left bottom mirror)
			)
		)
		(fp_text user "Author: Antmicro"
			(at -0.939 -3.399 0)
			(layer "B.Fab")
			(effects
				(font
					(size 0.7 0.7)
					(thickness 0.15)
				)
				(justify left bottom mirror)
			)
		)
		(fp_text user "${REFERENCE}"
			(at -0.939 -4.599 0)
			(layer "B.Fab")
			(effects
				(font
					(size 0.7 0.7)
					(thickness 0.15)
				)
				(justify left bottom mirror)
			)
		)
		(pad "1" smd roundrect
			(at -0.48 0 180)
			(size 0.59 0.64)
			(layers "B.Cu" "B.Mask" "B.Paste")
			(roundrect_rratio 0.25)
			(net 23 "GND")
			(pintype "passive")
		)
		(pad "2" smd roundrect
			(at 0.48 0 180)
			(size 0.59 0.64)
			(layers "B.Cu" "B.Mask" "B.Paste")
			(roundrect_rratio 0.25)
			(net 12 "XFI_VDD")
			(pintype "passive")
		)
	)
	(footprint "antmicro-footprints:TP_SMD_0.75mm"
		(layer "B.Cu")
		(at 120.5 86 90)
		(property "Reference" "TP1"
			(at 0.8 1.5 270)
			(layer "B.SilkS")
			(effects
				(font
					(size 0.7 0.7)
					(thickness 0.15)
				)
				(justify left bottom mirror)
			)
		)
		(property "Value" "TP_0.75mm_SMD"
			(at 0 -1.2 270)
			(layer "B.Fab")
			(effects
				(font
					(size 0.7 0.7)
					(thickness 0.15)
				)
				(justify left bottom mirror)
			)
		)
		(property "Description" "SMT test point"
			(at 0 0 270)
			(layer "B.Fab")
			(hide yes)
			(effects
				(font
					(size 1.27 1.27)
					(thickness 0.15)
				)
				(justify mirror)
			)
		)
		(property "License" "Apache-2.0"
			(at 0 0 90)
			(unlocked yes)
			(layer "B.Fab")
			(hide yes)
			(effects
				(font
					(size 1 1)
					(thickness 0.15)
				)
				(justify mirror)
			)
		)
		(property "Manufacturer" ""
			(at 0 0 90)
			(unlocked yes)
			(layer "B.Fab")
			(hide yes)
			(effects
				(font
					(size 1 1)
					(thickness 0.15)
				)
				(justify mirror)
			)
		)
		(property "MPN" ""
			(at 0 0 90)
			(unlocked yes)
			(layer "B.Fab")
			(hide yes)
			(effects
				(font
					(size 1 1)
					(thickness 0.15)
				)
				(justify mirror)
			)
		)
		(property "Author" "Antmicro"
			(at 0 0 90)
			(unlocked yes)
			(layer "B.Fab")
			(hide yes)
			(effects
				(font
					(size 1 1)
					(thickness 0.15)
				)
				(justify mirror)
			)
		)
		(sheetname "/PD and TB DC-DC/")
		(sheetfile "PD_and_TB_DC_DC.kicad_sch")
		(attr exclude_from_pos_files exclude_from_bom)
		(fp_circle
			(center 0 0)
			(end 0.475 0)
			(stroke
				(width 0.05)
				(type default)
			)
			(fill no)
			(layer "B.CrtYd")
		)
		(fp_text user "${REFERENCE}"
			(at -0.4 -2.7 270)
			(layer "B.Fab")
			(effects
				(font
					(size 0.7 0.7)
					(thickness 0.15)
				)
				(justify left bottom mirror)
			)
		)
		(fp_text user "License: Apache-2.0"
			(at -0.4 -5.101 270)
			(layer "B.Fab")
			(effects
				(font
					(size 0.7 0.7)
					(thickness 0.15)
				)
				(justify left bottom mirror)
			)
		)
		(fp_text user "Author: Antmicro"
			(at -0.4 -3.901 270)
			(layer "B.Fab")
			(effects
				(font
					(size 0.7 0.7)
					(thickness 0.15)
				)
				(justify left bottom mirror)
			)
		)
		(pad "1" smd circle
			(at 0 0 90)
			(size 0.75 0.75)
			(layers "B.Cu" "B.Mask")
			(net 53 "+5V_USB")
			(pinfunction "1")
			(pintype "passive")
		)
	)
	(footprint "antmicro-footprints:R_0402_1005Metric"
		(layer "B.Cu")
		(at 120 94.75 180)
		(descr "Resistor SMD 0402")
		(tags "resistor SMD 0402")
		(property "Reference" "R73"
			(at -0.7 -5.6 0)
			(layer "B.SilkS")
			(effects
				(font
					(size 0.7 0.7)
					(thickness 0.15)
				)
				(justify left bottom mirror)
			)
		)
		(property "Value" "R_100k_0402"
			(at -1.011843 -1.772047 0)
			(layer "B.Fab")
			(effects
				(font
					(size 0.7 0.7)
					(thickness 0.15)
				)
				(justify left bottom mirror)
			)
		)
		(property "Datasheet" "https://www.bourns.com/docs/product-datasheets/cr.pdf"
			(at 0 0 0)
			(layer "B.Fab")
			(hide yes)
			(effects
				(font
					(size 1.27 1.27)
					(thickness 0.15)
				)
				(justify mirror)
			)
		)
		(property "Description" "SMD Chip Resistor, 100 kohm, ± 1%, 62.5 mW, 0402 [1005 Metric], Thick Film, General Purpose"
			(at 0 0 0)
			(layer "B.Fab")
			(hide yes)
			(effects
				(font
					(size 1.27 1.27)
					(thickness 0.15)
				)
				(justify mirror)
			)
		)
		(property "MPN" "CR0402-FX-1003GLF"
			(at 0 0 180)
			(unlocked yes)
			(layer "B.Fab")
			(hide yes)
			(effects
				(font
					(size 1 1)
					(thickness 0.15)
				)
				(justify mirror)
			)
		)
		(property "Manufacturer" "Bourns"
			(at 0 0 180)
			(unlocked yes)
			(layer "B.Fab")
			(hide yes)
			(effects
				(font
					(size 1 1)
					(thickness 0.15)
				)
				(justify mirror)
			)
		)
		(property "License" "Apache-2.0"
			(at 0 0 180)
			(unlocked yes)
			(layer "B.Fab")
			(hide yes)
			(effects
				(font
					(size 1 1)
					(thickness 0.15)
				)
				(justify mirror)
			)
		)
		(property "Val" "100k"
			(at 0 0 180)
			(unlocked yes)
			(layer "B.Fab")
			(hide yes)
			(effects
				(font
					(size 1 1)
					(thickness 0.15)
				)
				(justify mirror)
			)
		)
		(property "Tolerance" "1%"
			(at 0 0 180)
			(unlocked yes)
			(layer "B.Fab")
			(hide yes)
			(effects
				(font
					(size 1 1)
					(thickness 0.15)
				)
				(justify mirror)
			)
		)
		(property "Author" "Antmicro"
			(at 0 0 180)
			(unlocked yes)
			(layer "B.Fab")
			(hide yes)
			(effects
				(font
					(size 1 1)
					(thickness 0.15)
				)
				(justify mirror)
			)
		)
		(sheetname "/TB Controller - Power/")
		(sheetfile "tb-power.kicad_sch")
		(attr smd)
		(fp_rect
			(start -0.925 0.47)
			(end 0.925 -0.47)
			(stroke
				(width 0.05)
				(type default)
			)
			(fill no)
			(layer "B.CrtYd")
		)
		(fp_rect
			(start -0.5 0.25)
			(end 0.5 -0.25)
			(stroke
				(width 0.15)
				(type solid)
			)
			(fill no)
			(layer "B.Fab")
		)
		(fp_text user "Author: Antmicro"
			(at -0.95 -4.169 0)
			(layer "B.Fab")
			(effects
				(font
					(size 0.7 0.7)
					(thickness 0.15)
				)
				(justify left bottom mirror)
			)
		)
		(fp_text user "${REFERENCE}"
			(at -0.95 -3.168 0)
			(layer "B.Fab")
			(effects
				(font
					(size 0.7 0.7)
					(thickness 0.15)
				)
				(justify left bottom mirror)
			)
		)
		(fp_text user "License: Apache-2.0"
			(at -0.95 -5.169 0)
			(layer "B.Fab")
			(effects
				(font
					(size 0.7 0.7)
					(thickness 0.15)
				)
				(justify left bottom mirror)
			)
		)
		(pad "1" smd roundrect
			(at -0.48 0 180)
			(size 0.59 0.64)
			(layers "B.Cu" "B.Mask" "B.Paste")
			(roundrect_rratio 0.25)
			(net 23 "GND")
			(pintype "passive")
		)
		(pad "2" smd roundrect
			(at 0.48 0 180)
			(size 0.59 0.64)
			(layers "B.Cu" "B.Mask" "B.Paste")
			(roundrect_rratio 0.25)
			(net 196 "Net-(Q1-B)")
			(pintype "passive")
		)
	)
	(footprint "antmicro-footprints:C_0402_1005Metric"
		(layer "B.Cu")
		(at 147.481865 80.260117 180)
		(descr "Capacitor SMD 0402")
		(tags "capacitor SMD 0402")
		(property "Reference" "C212"
			(at -18.618135 -9.464883 0)
			(layer "B.SilkS")
			(effects
				(font
					(size 0.7 0.7)
					(thickness 0.15)
				)
				(justify mirror)
			)
		)
		(property "Value" "C_1u_25V_0402"
			(at -1.022927 -2.155213 0)
			(layer "B.Fab")
			(effects
				(font
					(size 0.7 0.7)
					(thickness 0.15)
				)
				(justify left bottom mirror)
			)
		)
		(property "Datasheet" "https://www.murata.com/products/productdetail?partno=GRM155R61E105KE11%23"
			(at 0 0 0)
			(layer "B.Fab")
			(hide yes)
			(effects
				(font
					(size 1.27 1.27)
					(thickness 0.15)
				)
				(justify mirror)
			)
		)
		(property "Description" "SMD Multilayer Ceramic Capacitor, 1 µF, 25 V, 0402 [1005 Metric], ± 10%, X5R, GRM Series"
			(at 0 0 0)
			(layer "B.Fab")
			(hide yes)
			(effects
				(font
					(size 1.27 1.27)
					(thickness 0.15)
				)
				(justify mirror)
			)
		)
		(property "MPN" "GRM155R61E105KE11J"
			(at 0 0 180)
			(unlocked yes)
			(layer "B.Fab")
			(hide yes)
			(effects
				(font
					(size 1 1)
					(thickness 0.15)
				)
				(justify mirror)
			)
		)
		(property "Manufacturer" "Murata"
			(at 0 0 180)
			(unlocked yes)
			(layer "B.Fab")
			(hide yes)
			(effects
				(font
					(size 1 1)
					(thickness 0.15)
				)
				(justify mirror)
			)
		)
		(property "License" "Apache-2.0"
			(at 0 0 180)
			(unlocked yes)
			(layer "B.Fab")
			(hide yes)
			(effects
				(font
					(size 1 1)
					(thickness 0.15)
				)
				(justify mirror)
			)
		)
		(property "Author" "Antmicro"
			(at 0 0 180)
			(unlocked yes)
			(layer "B.Fab")
			(hide yes)
			(effects
				(font
					(size 1 1)
					(thickness 0.15)
				)
				(justify mirror)
			)
		)
		(property "Val" "1u"
			(at 0 0 180)
			(unlocked yes)
			(layer "B.Fab")
			(hide yes)
			(effects
				(font
					(size 1 1)
					(thickness 0.15)
				)
				(justify mirror)
			)
		)
		(property "Voltage" "25V"
			(at 0 0 180)
			(unlocked yes)
			(layer "B.Fab")
			(hide yes)
			(effects
				(font
					(size 1 1)
					(thickness 0.15)
				)
				(justify mirror)
			)
		)
		(property "Dielectric" "X5R"
			(at 0 0 180)
			(unlocked yes)
			(layer "B.Fab")
			(hide yes)
			(effects
				(font
					(size 1 1)
					(thickness 0.15)
				)
				(justify mirror)
			)
		)
		(sheetname "/X710-AT2 power/")
		(sheetfile "x710-at2-power.kicad_sch")
		(attr smd)
		(fp_rect
			(start -0.925 0.47)
			(end 0.925 -0.47)
			(stroke
				(width 0.05)
				(type default)
			)
			(fill no)
			(layer "B.CrtYd")
		)
		(fp_line
			(start 0.504 0.25)
			(end 0.504 -0.248)
			(stroke
				(width 0.15)
				(type solid)
			)
			(layer "B.Fab")
		)
		(fp_line
			(start 0.504 -0.248)
			(end -0.494 -0.248)
			(stroke
				(width 0.15)
				(type solid)
			)
			(layer "B.Fab")
		)
		(fp_line
			(start -0.494 0.25)
			(end 0.504 0.25)
			(stroke
				(width 0.15)
				(type solid)
			)
			(layer "B.Fab")
		)
		(fp_line
			(start -0.494 -0.248)
			(end -0.494 0.25)
			(stroke
				(width 0.15)
				(type solid)
			)
			(layer "B.Fab")
		)
		(fp_text user "License: Apache-2.0"
			(at -0.939 -5.799 0)
			(layer "B.Fab")
			(effects
				(font
					(size 0.7 0.7)
					(thickness 0.15)
				)
				(justify left bottom mirror)
			)
		)
		(fp_text user "${REFERENCE}"
			(at -0.939 -4.599 0)
			(layer "B.Fab")
			(effects
				(font
					(size 0.7 0.7)
					(thickness 0.15)
				)
				(justify left bottom mirror)
			)
		)
		(fp_text user "Author: Antmicro"
			(at -0.939 -3.399 0)
			(layer "B.Fab")
			(effects
				(font
					(size 0.7 0.7)
					(thickness 0.15)
				)
				(justify left bottom mirror)
			)
		)
		(pad "1" smd roundrect
			(at -0.48 0 180)
			(size 0.59 0.64)
			(layers "B.Cu" "B.Mask" "B.Paste")
			(roundrect_rratio 0.25)
			(net 23 "GND")
			(pintype "passive")
		)
		(pad "2" smd roundrect
			(at 0.48 0 180)
			(size 0.59 0.64)
			(layers "B.Cu" "B.Mask" "B.Paste")
			(roundrect_rratio 0.25)
			(net 9 "VCCD")
			(pintype "passive")
		)
	)
	(footprint "antmicro-footprints:R_0402_1005Metric"
		(layer "B.Cu")
		(at 158.831866 75.760117 180)
		(descr "Resistor SMD 0402")
		(tags "resistor SMD 0402")
		(property "Reference" "R162"
			(at -20.168136 -8.989883 0)
			(layer "B.SilkS")
			(effects
				(font
					(size 0.7 0.7)
					(thickness 0.15)
				)
				(justify mirror)
			)
		)
		(property "Value" "R_1k_0402"
			(at -1.011843 -1.772047 0)
			(layer "B.Fab")
			(effects
				(font
					(size 0.7 0.7)
					(thickness 0.15)
				)
				(justify left bottom mirror)
			)
		)
		(property "Datasheet" "https://www.bourns.com/docs/product-datasheets/cr.pdf"
			(at 0 0 0)
			(layer "B.Fab")
			(hide yes)
			(effects
				(font
					(size 1.27 1.27)
					(thickness 0.15)
				)
				(justify mirror)
			)
		)
		(property "Description" "SMD Chip Resistor, 1 kohm, ± 1%, 63 mW, 0402 [1005 Metric], Thick Film, General Purpose"
			(at 0 0 0)
			(layer "B.Fab")
			(hide yes)
			(effects
				(font
					(size 1.27 1.27)
					(thickness 0.15)
				)
				(justify mirror)
			)
		)
		(property "MPN" "CR0402-FX-1001GLF"
			(at 0 0 180)
			(unlocked yes)
			(layer "B.Fab")
			(hide yes)
			(effects
				(font
					(size 1 1)
					(thickness 0.15)
				)
				(justify mirror)
			)
		)
		(property "Manufacturer" "Bourns"
			(at 0 0 180)
			(unlocked yes)
			(layer "B.Fab")
			(hide yes)
			(effects
				(font
					(size 1 1)
					(thickness 0.15)
				)
				(justify mirror)
			)
		)
		(property "License" "Apache-2.0"
			(at 0 0 180)
			(unlocked yes)
			(layer "B.Fab")
			(hide yes)
			(effects
				(font
					(size 1 1)
					(thickness 0.15)
				)
				(justify mirror)
			)
		)
		(property "Author" "Antmicro"
			(at 0 0 180)
			(unlocked yes)
			(layer "B.Fab")
			(hide yes)
			(effects
				(font
					(size 1 1)
					(thickness 0.15)
				)
				(justify mirror)
			)
		)
		(property "Val" "1k"
			(at 0 0 180)
			(unlocked yes)
			(layer "B.Fab")
			(hide yes)
			(effects
				(font
					(size 1 1)
					(thickness 0.15)
				)
				(justify mirror)
			)
		)
		(property "Tolerance" "1%"
			(at 0 0 180)
			(unlocked yes)
			(layer "B.Fab")
			(hide yes)
			(effects
				(font
					(size 1 1)
					(thickness 0.15)
				)
				(justify mirror)
			)
		)
		(sheetname "/X710-AT2 Misc/")
		(sheetfile "x710-at2-mics.kicad_sch")
		(attr smd)
		(fp_rect
			(start -0.925 0.47)
			(end 0.925 -0.47)
			(stroke
				(width 0.05)
				(type default)
			)
			(fill no)
			(layer "B.CrtYd")
		)
		(fp_rect
			(start -0.5 0.25)
			(end 0.5 -0.25)
			(stroke
				(width 0.15)
				(type solid)
			)
			(fill no)
			(layer "B.Fab")
		)
		(fp_text user "${REFERENCE}"
			(at -0.95 -3.168 0)
			(layer "B.Fab")
			(effects
				(font
					(size 0.7 0.7)
					(thickness 0.15)
				)
				(justify left bottom mirror)
			)
		)
		(fp_text user "Author: Antmicro"
			(at -0.95 -4.169 0)
			(layer "B.Fab")
			(effects
				(font
					(size 0.7 0.7)
					(thickness 0.15)
				)
				(justify left bottom mirror)
			)
		)
		(fp_text user "License: Apache-2.0"
			(at -0.95 -5.169 0)
			(layer "B.Fab")
			(effects
				(font
					(size 0.7 0.7)
					(thickness 0.15)
				)
				(justify left bottom mirror)
			)
		)
		(pad "1" smd roundrect
			(at -0.48 0 180)
			(size 0.59 0.64)
			(layers "B.Cu" "B.Mask" "B.Paste")
			(roundrect_rratio 0.25)
			(net 23 "GND")
			(pintype "passive")
		)
		(pad "2" smd roundrect
			(at 0.48 0 180)
			(size 0.59 0.64)
			(layers "B.Cu" "B.Mask" "B.Paste")
			(roundrect_rratio 0.25)
			(net 132 "/X710-AT2 Misc/XTAL_BYPASS")
			(pintype "passive")
		)
	)
)
